(kicad_pcb
	(version 20260206)
	(generator "pcbnew")
	(generator_version "10.0")
	(general
		(thickness 1.6)
		(legacy_teardrops no)
	)
	(paper "A4")
	(title_block
		(title "Wiwynn_Tioga_Pass_MB.brd")
		(comment 1 "Tioga Pass / footprints 863-864 of 4770")
	)
	(layers
		(0 "F.Cu" signal "TOP")
		(4 "In1.Cu" signal "L2GND")
		(6 "In2.Cu" signal "L3")
		(8 "In3.Cu" signal "L4GND")
		(10 "In4.Cu" signal "L5")
		(12 "In5.Cu" signal "L6GND")
		(14 "In6.Cu" signal "L7VCC")
		(16 "In7.Cu" signal "L8VCC")
		(18 "In8.Cu" signal "L9GND")
		(20 "In9.Cu" signal "L10")
		(22 "In10.Cu" signal "L11GND")
		(24 "In11.Cu" signal "L12")
		(26 "In12.Cu" signal "L13GND")
		(2 "B.Cu" signal "BOTTOM")
		(9 "F.Adhes" user "F.Adhesive")
		(11 "B.Adhes" user "B.Adhesive")
		(13 "F.Paste" user "Package Geometry/Pastemask Top")
		(15 "B.Paste" user "Package Geometry/Pastemask Bottom")
		(5 "F.SilkS" user "Ref Des/Silkscreen Top")
		(7 "B.SilkS" user "Ref Des/Silkscreen Bottom")
		(1 "F.Mask" user "Board Geometry/Soldermask Top")
		(3 "B.Mask" user "Board Geometry/Soldermask Bottom")
		(17 "Dwgs.User" user "User.Drawings")
		(19 "Cmts.User" user "User.Comments")
		(21 "Eco1.User" user "User.Eco1")
		(23 "Eco2.User" user "User.Eco2")
		(25 "Edge.Cuts" user "Board Geometry/Outline")
		(27 "Margin" user)
		(31 "F.CrtYd" user "Package Geometry/Place Bound Top")
		(29 "B.CrtYd" user "Package Geometry/Place Bound Bottom")
		(35 "F.Fab" user "Ref Des/Assembly Top")
		(33 "B.Fab" user "Ref Des/Assembly Bottom")
	)
	(footprint ""
		(layer "F.Cu")
		(at 157.988 -119.166386 90)
		(property "Reference" "R3B4"
			(at 0 0 90)
			(layer "F.SilkS")
			(hide yes)
			(effects
				(font
					(size 1.27 1.27)
				)
			)
		)
		(property "Value" ""
			(at 0 0 90)
			(layer "F.Fab")
			(effects
				(font
					(size 1.27 1.27)
				)
			)
		)
		(duplicate_pad_numbers_are_jumpers no)
		(fp_poly
			(pts
				(xy -0.2794 -0.1016) (xy 0.2794 -0.1016) (xy 0.2794 0.9906) (xy -0.2794 0.9906)
			)
			(stroke
				(width 0)
				(type default)
			)
			(fill no)
			(layer "F.CrtYd")
		)
		(fp_line
			(start 0.2794 -0.1016)
			(end -0.2794 -0.1016)
			(stroke
				(width 0.1)
				(type default)
			)
			(layer "F.Fab")
		)
		(fp_line
			(start -0.2794 -0.1016)
			(end -0.2794 0.9906)
			(stroke
				(width 0.1)
				(type default)
			)
			(layer "F.Fab")
		)
		(fp_line
			(start 0.2794 0.9906)
			(end 0.2794 -0.1016)
			(stroke
				(width 0.1)
				(type default)
			)
			(layer "F.Fab")
		)
		(fp_line
			(start -0.2794 0.9906)
			(end 0.2794 0.9906)
			(stroke
				(width 0.1)
				(type default)
			)
			(layer "F.Fab")
		)
		(pad "1" smd rect
			(at 0 0 90)
			(size 0.508 0.508)
			(layers "F.Cu" "F.Mask" "F.Paste")
			(net "SVID_DIO0_CPU1_R")
		)
		(pad "2" smd rect
			(at 0 0.889 90)
			(size 0.508 0.508)
			(layers "F.Cu" "F.Mask" "F.Paste")
			(net "PVCCIO_CPU1")
		)
		(zone
			(layer "F.Cu")
			(hatch none 0.5)
			(connect_pads
				(clearance 0)
			)
			(min_thickness 0.25)
			(keepout
				(tracks allowed)
				(vias not_allowed)
				(pads allowed)
				(copperpour not_allowed)
				(footprints allowed)
			)
			(placement
				(enabled no)
				(sheetname "")
			)
			(fill
				(thermal_gap 0.5)
				(thermal_bridge_width 0.5)
				(island_removal_mode 0)
			)
			(polygon
				(pts
					(xy 158.242 -118.912386) (xy 158.242 -119.420386) (xy 158.623 -119.420386) (xy 158.623 -118.912386)
				)
			)
		)
		(zone
			(layer "F.Cu")
			(hatch none 0.5)
			(connect_pads
				(clearance 0)
			)
			(min_thickness 0.25)
			(keepout
				(tracks not_allowed)
				(vias allowed)
				(pads allowed)
				(copperpour not_allowed)
				(footprints allowed)
			)
			(placement
				(enabled no)
				(sheetname "")
			)
			(fill
				(thermal_gap 0.5)
				(thermal_bridge_width 0.5)
				(island_removal_mode 0)
			)
			(polygon
				(pts
					(xy 158.623 -118.912386) (xy 158.623 -119.420386) (xy 158.242 -119.420386) (xy 158.242 -118.912386)
				)
			)
		)
	)
	(footprint ""
		(layer "F.Cu")
		(at 198.925434 -65.167764 90)
		(property "Reference" "EU4D6"
			(at 3.334766 -1.542034 0)
			(unlocked yes)
			(layer "F.SilkS")
			(effects
				(font
					(size 0.7874 0.5842)
					(thickness 0.1524)
				)
			)
		)
		(property "Value" ""
			(at 0 0 90)
			(layer "F.Fab")
			(effects
				(font
					(size 1.27 1.27)
				)
			)
		)
		(duplicate_pad_numbers_are_jumpers no)
		(fp_line
			(start 2.9718 -3.5052)
			(end 2.9718 3.429)
			(stroke
				(width 0.1524)
				(type default)
			)
			(layer "F.SilkS")
		)
		(fp_line
			(start -3.0099 -3.5052)
			(end 2.9718 -3.5052)
			(stroke
				(width 0.1524)
				(type default)
			)
			(layer "F.SilkS")
		)
		(fp_line
			(start 2.9718 3.429)
			(end -3.0099 3.429)
			(stroke
				(width 0.1524)
				(type default)
			)
			(layer "F.SilkS")
		)
		(fp_line
			(start -3.0099 3.429)
			(end -3.0099 -3.5052)
			(stroke
				(width 0.1524)
				(type default)
			)
			(layer "F.SilkS")
		)
		(fp_circle
			(center -3.057398 -2.678684)
			(end -3.057398 -2.551684)
			(stroke
				(width 0.254)
				(type default)
			)
			(fill no)
			(layer "F.SilkS")
		)
		(fp_poly
			(pts
				(xy -2.9972 -3.4925) (xy -2.9972 -2.6924) (xy -2.1971 -3.4925)
			)
			(stroke
				(width 0)
				(type default)
			)
			(fill yes)
			(layer "F.SilkS")
		)
		(fp_poly
			(pts
				(xy -2.549906 -3.050032) (xy -2.549906 3.050032) (xy 2.549906 3.050032) (xy 2.549906 -3.050032)
			)
			(stroke
				(width 0)
				(type default)
			)
			(fill no)
			(layer "F.CrtYd")
		)
		(fp_line
			(start 2.549906 -3.050032)
			(end 2.549906 3.050032)
			(stroke
				(width 0.1)
				(type default)
			)
			(layer "F.Fab")
		)
		(fp_line
			(start -2.549906 -3.050032)
			(end 2.549906 -3.050032)
			(stroke
				(width 0.1)
				(type default)
			)
			(layer "F.Fab")
		)
		(fp_line
			(start 2.549906 3.050032)
			(end -2.549906 3.050032)
			(stroke
				(width 0.1)
				(type default)
			)
			(layer "F.Fab")
		)
		(fp_line
			(start -2.549906 3.050032)
			(end -2.549906 -3.050032)
			(stroke
				(width 0.1)
				(type default)
			)
			(layer "F.Fab")
		)
		(fp_circle
			(center -3.057398 -2.678684)
			(end -3.057398 -2.551684)
			(stroke
				(width 0.254)
				(type default)
			)
			(fill no)
			(layer "F.Fab")
		)
		(pad "1" smd rect
			(at -2.39522 -2.279904 90)
			(size 0.7112 0.254)
			(layers "F.Cu" "F.Mask" "F.Paste")
			(net "PVCCIN_CPU0")
		)
		(pad "2" smd rect
			(at -2.39522 -1.83007 90)
			(size 0.7112 0.254)
			(layers "F.Cu" "F.Mask" "F.Paste")
			(net "GND")
		)
		(pad "3" smd rect
			(at -2.39522 -1.379982 90)
			(size 0.7112 0.254)
			(layers "F.Cu" "F.Mask" "F.Paste")
			(net "VR_PVCCIN_CPU0_PH2_VCIN")
		)
		(pad "4" smd rect
			(at -2.39522 -0.929894 90)
			(size 0.7112 0.254)
			(layers "F.Cu" "F.Mask" "F.Paste")
			(net "P5V_STBY")
		)
		(pad "5" smd rect
			(at -2.39522 -0.48006 90)
			(size 0.7112 0.254)
			(layers "F.Cu" "F.Mask" "F.Paste")
			(net "GND")
		)
		(pad "6" smd rect
			(at -2.39522 -0.029972 90)
			(size 0.7112 0.254)
			(layers "F.Cu" "F.Mask" "F.Paste")
			(net "TP_PVCCIN_CPU0_PH2_GL_0")
		)
		(pad "7" smd custom
			(at 0.016764 1.145032 90)
			(size 0.53975 0.53975)
			(layers "F.Cu" "F.Mask" "F.Paste")
			(net "GND")
			(options
				(clearance outline)
				(anchor circle)
			)
			(primitives
				(gr_poly
					(pts
						(xy -2.7051 1.0795) (xy -2.7051 -0.3683) (xy -0.9271 -0.3683) (xy -0.9271 -1.0795) (xy 2.7051 -1.0795)
						(xy 2.7051 1.0795)
					)
					(width 0)
					(fill yes)
				)
			)
		)
		(pad "10" smd rect
			(at -0.008382 2.874772 90)
			(size 4.3434 0.6096)
			(layers "F.Cu" "F.Mask" "F.Paste")
			(net "VR_PVCCIN_CPU0_PHASE2")
		)
		(pad "25" smd rect
			(at 1.548384 -1.283208 90)
			(size 2.3368 2.0066)
			(layers "F.Cu" "F.Mask" "F.Paste")
			(net "VR_FET_SW_P12V_STBY_PVCCIN_CPU0")
		)
		(pad "30" smd rect
			(at 2.050034 -2.895092 90)
			(size 0.254 0.7112)
			(layers "F.Cu" "F.Mask" "F.Paste")
			(net "VR_FET_SW_P12V_STBY_PVCCIN_CPU0")
		)
		(pad "31" smd rect
			(at 1.599946 -2.895092 90)
			(size 0.254 0.7112)
			(layers "F.Cu" "F.Mask" "F.Paste")
			(net "Net_362")
		)
		(pad "32" smd rect
			(at 1.150112 -2.895092 90)
			(size 0.254 0.7112)
			(layers "F.Cu" "F.Mask" "F.Paste")
			(net "VR_PVCCIN_CPU0_PH2_PHASE")
		)
		(pad "33" smd rect
			(at 0.700024 -2.895092 90)
			(size 0.254 0.7112)
			(layers "F.Cu" "F.Mask" "F.Paste")
			(net "VR_PVCCIN_CPU0_PH2_BOOT_R")
		)
		(pad "34" smd rect
			(at 0.249936 -2.895092 90)
			(size 0.254 0.7112)
			(layers "F.Cu" "F.Mask" "F.Paste")
			(net "VR_PVCCIN_CPU0_PWM2")
		)
		(pad "35" smd rect
			(at -0.199898 -2.895092 90)
			(size 0.254 0.7112)
			(layers "F.Cu" "F.Mask" "F.Paste")
			(net "P5V_STBY")
		)
		(pad "36" smd rect
			(at -0.649986 -2.895092 90)
			(size 0.254 0.7112)
			(layers "F.Cu" "F.Mask" "F.Paste")
			(net "A_TSENSE_PVCCIN_CPU0")
		)
		(pad "37" smd rect
			(at -1.100074 -2.895092 90)
			(size 0.254 0.7112)
			(layers "F.Cu" "F.Mask" "F.Paste")
			(net "VR_PVCCIN_CPU0_PH2_OCSET")
		)
		(pad "38" smd rect
			(at -1.549908 -2.895092 90)
			(size 0.254 0.7112)
			(layers "F.Cu" "F.Mask" "F.Paste")
			(net "ISENSE_PVCCIN_CPU0_PH2_IMON")
		)
		(pad "39" smd rect
			(at -1.999996 -2.895092 90)
			(size 0.254 0.7112)
			(layers "F.Cu" "F.Mask" "F.Paste")
			(net "VR_PVCCIN_CPU0_AIREF2")
		)
		(pad "40" smd rect
			(at -0.871728 -1.283208 90)
			(size 1.8034 2.0066)
			(layers "F.Cu" "F.Mask" "F.Paste")
			(net "GND")
		)
		(pad "41" smd rect
			(at -1.533906 0.247904 90)
			(size 0.508 0.3556)
			(layers "F.Cu" "F.Mask" "F.Paste")
			(net "TP_PVCCIN_CPU0_PH2_GL_1")
		)
	)
)
